# S9S_MB_2U (Grand Teton) — schematic netlist excerpt (pin names and nets, part order shuffled) for the footprints in the layout excerpt that follows; sources: Cadence DE-HDL packaged netlist, KiCad conversion of 03242023_DA0F0TMBIJ0_F0T_Motherboard_J_brd_V01_OCP.brd

R1791  Q_RES  9.09K 1% CHIP  pkg 0402LF  page 250 : A = P5V_ADC ; B = GND
R1749  Q_RES  10K 1% EMPTY  pkg 0402LF  page 202 : A = FM_ESPI_PLD_R1_EN ; B = GND

(kicad_pcb
	(version 20260206)
	(generator "pcbnew")
	(generator_version "10.0")
	(general
		(thickness 1.6)
		(legacy_teardrops no)
	)
	(paper "A4")
	(title_block
		(title "03242023_DA0F0TMBIJ0_F0T_Motherboard_J_brd_V01_OCP.brd")
		(comment 1 "Grand Teton / footprints 1208-1209 of 6105")
	)
	(layers
		(0 "F.Cu" signal "TOP")
		(4 "In1.Cu" signal "GND")
		(6 "In2.Cu" signal "IN1")
		(8 "In3.Cu" signal "GND1")
		(10 "In4.Cu" signal "IN2")
		(12 "In5.Cu" signal "GND2")
		(14 "In6.Cu" signal "IN3")
		(16 "In7.Cu" signal "GND3")
		(18 "In8.Cu" signal "VCC")
		(20 "In9.Cu" signal "VCC1")
		(22 "In10.Cu" signal "GND4")
		(24 "In11.Cu" signal "IN4")
		(26 "In12.Cu" signal "GND5")
		(28 "In13.Cu" signal "IN5")
		(30 "In14.Cu" signal "GND6")
		(32 "In15.Cu" signal "IN6")
		(34 "In16.Cu" signal "GND7")
		(2 "B.Cu" signal "BOTTOM")
		(9 "F.Adhes" user "F.Adhesive")
		(11 "B.Adhes" user "B.Adhesive")
		(13 "F.Paste" user "Package Geometry/Pastemask Top")
		(15 "B.Paste" user "Package Geometry/Pastemask Bottom")
		(5 "F.SilkS" user "Ref Des/Silkscreen Top")
		(7 "B.SilkS" user "Ref Des/Silkscreen Bottom")
		(1 "F.Mask" user "Board Geometry/Soldermask Top")
		(3 "B.Mask" user "Board Geometry/Soldermask Bottom")
		(17 "Dwgs.User" user "User.Drawings")
		(19 "Cmts.User" user "User.Comments")
		(21 "Eco1.User" user "User.Eco1")
		(23 "Eco2.User" user "User.Eco2")
		(25 "Edge.Cuts" user "Board Geometry/Outline")
		(27 "Margin" user)
		(31 "F.CrtYd" user "Package Geometry/Place Bound Top")
		(29 "B.CrtYd" user "Package Geometry/Place Bound Bottom")
		(35 "F.Fab" user "Ref Des/Assembly Top")
		(33 "B.Fab" user "Ref Des/Assembly Bottom")
	)
	(footprint ""
		(layer "F.Cu")
		(at 333.702152 -16.2052 90)
		(property "Reference" "R1749"
			(at 0 0 90)
			(layer "F.SilkS")
			(hide yes)
			(effects
				(font
					(size 1.27 1.27)
				)
			)
		)
		(property "Value" ""
			(at 0 0 90)
			(layer "F.Fab")
			(effects
				(font
					(size 1.27 1.27)
				)
			)
		)
		(duplicate_pad_numbers_are_jumpers no)
		(fp_line
			(start 0.7874 -0.4064)
			(end 0.7874 0.4064)
			(stroke
				(width 0.1524)
				(type default)
			)
			(layer "F.SilkS")
		)
		(fp_line
			(start -0.7874 -0.4064)
			(end 0.7874 -0.4064)
			(stroke
				(width 0.1524)
				(type default)
			)
			(layer "F.SilkS")
		)
		(fp_line
			(start 0.7874 0.4064)
			(end -0.7874 0.4064)
			(stroke
				(width 0.1524)
				(type default)
			)
			(layer "F.SilkS")
		)
		(fp_line
			(start -0.7874 0.4064)
			(end -0.7874 -0.4064)
			(stroke
				(width 0.1524)
				(type default)
			)
			(layer "F.SilkS")
		)
		(fp_line
			(start -0.12065 -0.305054)
			(end -0.12065 -0.2794)
			(stroke
				(width 0.1)
				(type default)
			)
			(layer "F.Fab")
		)
		(fp_line
			(start -0.67945 -0.305054)
			(end -0.12065 -0.305054)
			(stroke
				(width 0.1)
				(type default)
			)
			(layer "F.Fab")
		)
		(fp_line
			(start 0.67945 -0.3048)
			(end 0.67945 0.3048)
			(stroke
				(width 0.1)
				(type default)
			)
			(layer "F.Fab")
		)
		(fp_line
			(start 0.12065 -0.3048)
			(end 0.67945 -0.3048)
			(stroke
				(width 0.1)
				(type default)
			)
			(layer "F.Fab")
		)
		(fp_line
			(start 0.12065 -0.2794)
			(end 0.12065 -0.3048)
			(stroke
				(width 0.1)
				(type default)
			)
			(layer "F.Fab")
		)
		(fp_line
			(start -0.12065 -0.2794)
			(end 0.12065 -0.2794)
			(stroke
				(width 0.1)
				(type default)
			)
			(layer "F.Fab")
		)
		(fp_line
			(start 0.120396 0.2794)
			(end -0.12065 0.2794)
			(stroke
				(width 0.1)
				(type default)
			)
			(layer "F.Fab")
		)
		(fp_line
			(start -0.12065 0.2794)
			(end -0.12065 0.3048)
			(stroke
				(width 0.1)
				(type default)
			)
			(layer "F.Fab")
		)
		(fp_line
			(start 0.67945 0.3048)
			(end 0.120396 0.3048)
			(stroke
				(width 0.1)
				(type default)
			)
			(layer "F.Fab")
		)
		(fp_line
			(start 0.120396 0.3048)
			(end 0.120396 0.2794)
			(stroke
				(width 0.1)
				(type default)
			)
			(layer "F.Fab")
		)
		(fp_line
			(start -0.12065 0.3048)
			(end -0.67945 0.3048)
			(stroke
				(width 0.1)
				(type default)
			)
			(layer "F.Fab")
		)
		(fp_line
			(start -0.67945 0.3048)
			(end -0.67945 -0.305054)
			(stroke
				(width 0.1)
				(type default)
			)
			(layer "F.Fab")
		)
		(pad "1" smd circle
			(at -0.40005 0 90)
			(size 0 0)
			(layers "F.Cu" "F.Mask" "F.Paste")
			(net "FM_ESPI_PLD_R1_EN")
		)
		(pad "2" smd circle
			(at 0.40005 0 90)
			(size 0 0)
			(layers "F.Cu" "F.Mask" "F.Paste")
			(net "GND")
		)
	)
	(footprint ""
		(layer "F.Cu")
		(at 44.169584 -109.444282)
		(property "Reference" "R1791"
			(at 0 0 0)
			(layer "F.SilkS")
			(hide yes)
			(effects
				(font
					(size 1.27 1.27)
				)
			)
		)
		(property "Value" ""
			(at 0 0 0)
			(layer "F.Fab")
			(effects
				(font
					(size 1.27 1.27)
				)
			)
		)
		(duplicate_pad_numbers_are_jumpers no)
		(fp_line
			(start -0.7874 -0.4064)
			(end 0.7874 -0.4064)
			(stroke
				(width 0.1524)
				(type default)
			)
			(layer "F.SilkS")
		)
		(fp_line
			(start -0.7874 0.4064)
			(end -0.7874 -0.4064)
			(stroke
				(width 0.1524)
				(type default)
			)
			(layer "F.SilkS")
		)
		(fp_line
			(start 0.7874 -0.4064)
			(end 0.7874 0.4064)
			(stroke
				(width 0.1524)
				(type default)
			)
			(layer "F.SilkS")
		)
		(fp_line
			(start 0.7874 0.4064)
			(end -0.7874 0.4064)
			(stroke
				(width 0.1524)
				(type default)
			)
			(layer "F.SilkS")
		)
		(fp_line
			(start -0.67945 -0.305054)
			(end -0.12065 -0.305054)
			(stroke
				(width 0.1)
				(type default)
			)
			(layer "F.Fab")
		)
		(fp_line
			(start -0.67945 0.3048)
			(end -0.67945 -0.305054)
			(stroke
				(width 0.1)
				(type default)
			)
			(layer "F.Fab")
		)
		(fp_line
			(start -0.12065 -0.305054)
			(end -0.12065 -0.2794)
			(stroke
				(width 0.1)
				(type default)
			)
			(layer "F.Fab")
		)
		(fp_line
			(start -0.12065 -0.2794)
			(end 0.12065 -0.2794)
			(stroke
				(width 0.1)
				(type default)
			)
			(layer "F.Fab")
		)
		(fp_line
			(start -0.12065 0.2794)
			(end -0.12065 0.3048)
			(stroke
				(width 0.1)
				(type default)
			)
			(layer "F.Fab")
		)
		(fp_line
			(start -0.12065 0.3048)
			(end -0.67945 0.3048)
			(stroke
				(width 0.1)
				(type default)
			)
			(layer "F.Fab")
		)
		(fp_line
			(start 0.120396 0.2794)
			(end -0.12065 0.2794)
			(stroke
				(width 0.1)
				(type default)
			)
			(layer "F.Fab")
		)
		(fp_line
			(start 0.120396 0.3048)
			(end 0.120396 0.2794)
			(stroke
				(width 0.1)
				(type default)
			)
			(layer "F.Fab")
		)
		(fp_line
			(start 0.12065 -0.3048)
			(end 0.67945 -0.3048)
			(stroke
				(width 0.1)
				(type default)
			)
			(layer "F.Fab")
		)
		(fp_line
			(start 0.12065 -0.2794)
			(end 0.12065 -0.3048)
			(stroke
				(width 0.1)
				(type default)
			)
			(layer "F.Fab")
		)
		(fp_line
			(start 0.67945 -0.3048)
			(end 0.67945 0.3048)
			(stroke
				(width 0.1)
				(type default)
			)
			(layer "F.Fab")
		)
		(fp_line
			(start 0.67945 0.3048)
			(end 0.120396 0.3048)
			(stroke
				(width 0.1)
				(type default)
			)
			(layer "F.Fab")
		)
		(pad "1" smd circle
			(at -0.40005 0)
			(size 0 0)
			(layers "F.Cu" "F.Mask" "F.Paste")
			(net "P5V_ADC")
		)
		(pad "2" smd circle
			(at 0.40005 0)
			(size 0 0)
			(layers "F.Cu" "F.Mask" "F.Paste")
			(net "GND")
		)
	)
)
